(kicad_pcb
	(version 20260206)
	(generator "pcbnew")
	(generator_version "10.0")
	(general
		(thickness 1.6)
		(legacy_teardrops no)
	)
	(paper "A4")
	(title_block
		(title "9054_F0T_PDB_BD_GPU_F_V04_1213_1550_OCP.brd")
		(comment 1 "Grand Teton / footprints 60-65 of 608")
	)
	(layers
		(0 "F.Cu" signal "TOP")
		(4 "In1.Cu" signal "GND")
		(6 "In2.Cu" signal "IN1")
		(8 "In3.Cu" signal "GND1")
		(10 "In4.Cu" signal "VCC")
		(12 "In5.Cu" signal "VCC1")
		(14 "In6.Cu" signal "GND2")
		(16 "In7.Cu" signal "IN2")
		(18 "In8.Cu" signal "GND3")
		(2 "B.Cu" signal "BOTTOM")
		(9 "F.Adhes" user "F.Adhesive")
		(11 "B.Adhes" user "B.Adhesive")
		(13 "F.Paste" user "Package Geometry/Pastemask Top")
		(15 "B.Paste" user "Package Geometry/Pastemask Bottom")
		(5 "F.SilkS" user "Ref Des/Silkscreen Top")
		(7 "B.SilkS" user "Ref Des/Silkscreen Bottom")
		(1 "F.Mask" user "Board Geometry/Soldermask Top")
		(3 "B.Mask" user "Board Geometry/Soldermask Bottom")
		(17 "Dwgs.User" user "User.Drawings")
		(19 "Cmts.User" user "User.Comments")
		(21 "Eco1.User" user "User.Eco1")
		(23 "Eco2.User" user "User.Eco2")
		(25 "Edge.Cuts" user "Board Geometry/Outline")
		(27 "Margin" user)
		(31 "F.CrtYd" user "Package Geometry/Place Bound Top")
		(29 "B.CrtYd" user "Package Geometry/Place Bound Bottom")
		(35 "F.Fab" user "Ref Des/Assembly Top")
		(33 "B.Fab" user "Ref Des/Assembly Bottom")
	)
	(footprint ""
		(layer "F.Cu")
		(at 413.512 -45.212 180)
		(property "Reference" "R55"
			(at 0 0 180)
			(layer "F.SilkS")
			(hide yes)
			(effects
				(font
					(size 1.27 1.27)
				)
			)
		)
		(property "Value" ""
			(at 0 0 180)
			(layer "F.Fab")
			(effects
				(font
					(size 1.27 1.27)
				)
			)
		)
		(duplicate_pad_numbers_are_jumpers no)
		(fp_line
			(start 0.7874 0.4064)
			(end -0.7874 0.4064)
			(stroke
				(width 0.1524)
				(type default)
			)
			(layer "F.SilkS")
		)
		(fp_line
			(start 0.7874 -0.4064)
			(end 0.7874 0.4064)
			(stroke
				(width 0.1524)
				(type default)
			)
			(layer "F.SilkS")
		)
		(fp_line
			(start -0.7874 0.4064)
			(end -0.7874 -0.4064)
			(stroke
				(width 0.1524)
				(type default)
			)
			(layer "F.SilkS")
		)
		(fp_line
			(start -0.7874 -0.4064)
			(end 0.7874 -0.4064)
			(stroke
				(width 0.1524)
				(type default)
			)
			(layer "F.SilkS")
		)
		(fp_line
			(start 0.67945 0.3048)
			(end 0.120396 0.3048)
			(stroke
				(width 0.1)
				(type default)
			)
			(layer "F.Fab")
		)
		(fp_line
			(start 0.67945 -0.3048)
			(end 0.67945 0.3048)
			(stroke
				(width 0.1)
				(type default)
			)
			(layer "F.Fab")
		)
		(fp_line
			(start 0.12065 -0.2794)
			(end 0.12065 -0.3048)
			(stroke
				(width 0.1)
				(type default)
			)
			(layer "F.Fab")
		)
		(fp_line
			(start 0.12065 -0.3048)
			(end 0.67945 -0.3048)
			(stroke
				(width 0.1)
				(type default)
			)
			(layer "F.Fab")
		)
		(fp_line
			(start 0.120396 0.3048)
			(end 0.120396 0.2794)
			(stroke
				(width 0.1)
				(type default)
			)
			(layer "F.Fab")
		)
		(fp_line
			(start 0.120396 0.2794)
			(end -0.12065 0.2794)
			(stroke
				(width 0.1)
				(type default)
			)
			(layer "F.Fab")
		)
		(fp_line
			(start -0.12065 0.3048)
			(end -0.67945 0.3048)
			(stroke
				(width 0.1)
				(type default)
			)
			(layer "F.Fab")
		)
		(fp_line
			(start -0.12065 0.2794)
			(end -0.12065 0.3048)
			(stroke
				(width 0.1)
				(type default)
			)
			(layer "F.Fab")
		)
		(fp_line
			(start -0.12065 -0.2794)
			(end 0.12065 -0.2794)
			(stroke
				(width 0.1)
				(type default)
			)
			(layer "F.Fab")
		)
		(fp_line
			(start -0.12065 -0.305054)
			(end -0.12065 -0.2794)
			(stroke
				(width 0.1)
				(type default)
			)
			(layer "F.Fab")
		)
		(fp_line
			(start -0.67945 0.3048)
			(end -0.67945 -0.305054)
			(stroke
				(width 0.1)
				(type default)
			)
			(layer "F.Fab")
		)
		(fp_line
			(start -0.67945 -0.305054)
			(end -0.12065 -0.305054)
			(stroke
				(width 0.1)
				(type default)
			)
			(layer "F.Fab")
		)
		(pad "1" smd circle
			(at -0.40005 0 180)
			(size 0 0)
			(layers "F.Cu" "F.Mask" "F.Paste")
			(net "PCA9555_A1")
		)
		(pad "2" smd circle
			(at 0.40005 0 180)
			(size 0 0)
			(layers "F.Cu" "F.Mask" "F.Paste")
			(net "GND")
		)
	)
	(footprint ""
		(layer "F.Cu")
		(at 153.162 -76.2 180)
		(property "Reference" "PC599"
			(at 0 0 180)
			(layer "F.SilkS")
			(hide yes)
			(effects
				(font
					(size 1.27 1.27)
				)
			)
		)
		(property "Value" ""
			(at 0 0 180)
			(layer "F.Fab")
			(effects
				(font
					(size 1.27 1.27)
				)
			)
		)
		(duplicate_pad_numbers_are_jumpers no)
		(fp_line
			(start 0.7874 0.4064)
			(end -0.7874 0.4064)
			(stroke
				(width 0.1524)
				(type default)
			)
			(layer "F.SilkS")
		)
		(fp_line
			(start 0.7874 -0.4064)
			(end 0.7874 0.4064)
			(stroke
				(width 0.1524)
				(type default)
			)
			(layer "F.SilkS")
		)
		(fp_line
			(start -0.7874 0.4064)
			(end -0.7874 -0.4064)
			(stroke
				(width 0.1524)
				(type default)
			)
			(layer "F.SilkS")
		)
		(fp_line
			(start -0.7874 -0.4064)
			(end 0.7874 -0.4064)
			(stroke
				(width 0.1524)
				(type default)
			)
			(layer "F.SilkS")
		)
		(fp_line
			(start 0.67945 0.3048)
			(end 0.120396 0.3048)
			(stroke
				(width 0.1)
				(type default)
			)
			(layer "F.Fab")
		)
		(fp_line
			(start 0.67945 -0.3048)
			(end 0.67945 0.3048)
			(stroke
				(width 0.1)
				(type default)
			)
			(layer "F.Fab")
		)
		(fp_line
			(start 0.12065 -0.2794)
			(end 0.12065 -0.3048)
			(stroke
				(width 0.1)
				(type default)
			)
			(layer "F.Fab")
		)
		(fp_line
			(start 0.12065 -0.3048)
			(end 0.67945 -0.3048)
			(stroke
				(width 0.1)
				(type default)
			)
			(layer "F.Fab")
		)
		(fp_line
			(start 0.120396 0.3048)
			(end 0.120396 0.2794)
			(stroke
				(width 0.1)
				(type default)
			)
			(layer "F.Fab")
		)
		(fp_line
			(start 0.120396 0.2794)
			(end -0.12065 0.2794)
			(stroke
				(width 0.1)
				(type default)
			)
			(layer "F.Fab")
		)
		(fp_line
			(start -0.12065 0.3048)
			(end -0.67945 0.3048)
			(stroke
				(width 0.1)
				(type default)
			)
			(layer "F.Fab")
		)
		(fp_line
			(start -0.12065 0.2794)
			(end -0.12065 0.3048)
			(stroke
				(width 0.1)
				(type default)
			)
			(layer "F.Fab")
		)
		(fp_line
			(start -0.12065 -0.2794)
			(end 0.12065 -0.2794)
			(stroke
				(width 0.1)
				(type default)
			)
			(layer "F.Fab")
		)
		(fp_line
			(start -0.12065 -0.305054)
			(end -0.12065 -0.2794)
			(stroke
				(width 0.1)
				(type default)
			)
			(layer "F.Fab")
		)
		(fp_line
			(start -0.67945 0.3048)
			(end -0.67945 -0.305054)
			(stroke
				(width 0.1)
				(type default)
			)
			(layer "F.Fab")
		)
		(fp_line
			(start -0.67945 -0.305054)
			(end -0.12065 -0.305054)
			(stroke
				(width 0.1)
				(type default)
			)
			(layer "F.Fab")
		)
		(pad "1" smd circle
			(at -0.40005 0 180)
			(size 0 0)
			(layers "F.Cu" "F.Mask" "F.Paste")
			(net "P52V_HS2_INTVCC")
		)
		(pad "2" smd circle
			(at 0.40005 0 180)
			(size 0 0)
			(layers "F.Cu" "F.Mask" "F.Paste")
			(net "GND")
		)
	)
	(footprint ""
		(layer "F.Cu")
		(at 442.595 -45.085)
		(property "Reference" "U21"
			(at 2.69367 0.381 90)
			(unlocked yes)
			(layer "F.SilkS")
			(effects
				(font
					(size 0.7874 0.5842)
					(thickness 0.1524)
				)
				(justify left)
			)
		)
		(property "Value" ""
			(at 0 0 0)
			(layer "F.Fab")
			(effects
				(font
					(size 1.27 1.27)
				)
			)
		)
		(duplicate_pad_numbers_are_jumpers no)
		(fp_line
			(start -2.032 -1.549908)
			(end 2.032 -1.549908)
			(stroke
				(width 0.1524)
				(type default)
			)
			(layer "F.SilkS")
		)
		(fp_line
			(start -2.032 1.549908)
			(end -2.032 -1.549908)
			(stroke
				(width 0.1524)
				(type default)
			)
			(layer "F.SilkS")
		)
		(fp_line
			(start 2.032 -1.549908)
			(end 2.032 1.549908)
			(stroke
				(width 0.1524)
				(type default)
			)
			(layer "F.SilkS")
		)
		(fp_line
			(start 2.032 1.549908)
			(end -2.032 1.549908)
			(stroke
				(width 0.1524)
				(type default)
			)
			(layer "F.SilkS")
		)
		(fp_poly
			(pts
				(xy -2.9718 -1.1176) (xy -2.9718 -0.6096) (xy -2.2098 -0.8636)
			)
			(stroke
				(width 0)
				(type default)
			)
			(fill yes)
			(layer "F.SilkS")
		)
		(fp_line
			(start -0.849884 -1.549908)
			(end -0.849884 1.549908)
			(stroke
				(width 0.1)
				(type default)
			)
			(layer "F.Fab")
		)
		(fp_line
			(start -0.849884 1.549908)
			(end 0.849884 1.549908)
			(stroke
				(width 0.1)
				(type default)
			)
			(layer "F.Fab")
		)
		(fp_line
			(start 0.849884 -1.549908)
			(end -0.849884 -1.549908)
			(stroke
				(width 0.1)
				(type default)
			)
			(layer "F.Fab")
		)
		(fp_line
			(start 0.849884 1.549908)
			(end 0.849884 -1.549908)
			(stroke
				(width 0.1)
				(type default)
			)
			(layer "F.Fab")
		)
		(fp_poly
			(pts
				(xy -2.9464 -1.2192) (xy -2.9464 -0.7112) (xy -2.1844 -0.9652)
			)
			(stroke
				(width 0)
				(type default)
			)
			(fill yes)
			(layer "F.Fab")
		)
		(pad "1" smd rect
			(at -1.225042 -0.94996 270)
			(size 0.4572 1.3208)
			(layers "F.Cu" "F.Mask" "F.Paste")
			(net "PWRGD_P3V3_AUX_MB_BUF_N")
		)
		(pad "2" smd rect
			(at -1.225042 0 270)
			(size 0.4572 1.3208)
			(layers "F.Cu" "F.Mask" "F.Paste")
			(net "GPU_HSC_EN")
		)
		(pad "3" smd rect
			(at -1.225042 0.94996 270)
			(size 0.4572 1.3208)
			(layers "F.Cu" "F.Mask" "F.Paste")
			(net "GND")
		)
		(pad "4" smd rect
			(at 1.225042 0.94996 270)
			(size 0.4572 1.3208)
			(layers "F.Cu" "F.Mask" "F.Paste")
			(net "GPU_HSC_BUF_R_EN")
		)
		(pad "5" smd rect
			(at 1.225042 -0.94996 270)
			(size 0.4572 1.3208)
			(layers "F.Cu" "F.Mask" "F.Paste")
			(net "P3V3_AUX")
		)
	)
	(footprint ""
		(layer "F.Cu")
		(at 448.437 -42.799)
		(property "Reference" "C1"
			(at 0 0 0)
			(layer "F.SilkS")
			(hide yes)
			(effects
				(font
					(size 1.27 1.27)
				)
			)
		)
		(property "Value" ""
			(at 0 0 0)
			(layer "F.Fab")
			(effects
				(font
					(size 1.27 1.27)
				)
			)
		)
		(duplicate_pad_numbers_are_jumpers no)
		(fp_line
			(start -0.7874 -0.4064)
			(end 0.7874 -0.4064)
			(stroke
				(width 0.1524)
				(type default)
			)
			(layer "F.SilkS")
		)
		(fp_line
			(start -0.7874 0.4064)
			(end -0.7874 -0.4064)
			(stroke
				(width 0.1524)
				(type default)
			)
			(layer "F.SilkS")
		)
		(fp_line
			(start 0.7874 -0.4064)
			(end 0.7874 0.4064)
			(stroke
				(width 0.1524)
				(type default)
			)
			(layer "F.SilkS")
		)
		(fp_line
			(start 0.7874 0.4064)
			(end -0.7874 0.4064)
			(stroke
				(width 0.1524)
				(type default)
			)
			(layer "F.SilkS")
		)
		(fp_line
			(start -0.67945 -0.305054)
			(end -0.12065 -0.305054)
			(stroke
				(width 0.1)
				(type default)
			)
			(layer "F.Fab")
		)
		(fp_line
			(start -0.67945 0.3048)
			(end -0.67945 -0.305054)
			(stroke
				(width 0.1)
				(type default)
			)
			(layer "F.Fab")
		)
		(fp_line
			(start -0.12065 -0.305054)
			(end -0.12065 -0.2794)
			(stroke
				(width 0.1)
				(type default)
			)
			(layer "F.Fab")
		)
		(fp_line
			(start -0.12065 -0.2794)
			(end 0.12065 -0.2794)
			(stroke
				(width 0.1)
				(type default)
			)
			(layer "F.Fab")
		)
		(fp_line
			(start -0.12065 0.2794)
			(end -0.12065 0.3048)
			(stroke
				(width 0.1)
				(type default)
			)
			(layer "F.Fab")
		)
		(fp_line
			(start -0.12065 0.3048)
			(end -0.67945 0.3048)
			(stroke
				(width 0.1)
				(type default)
			)
			(layer "F.Fab")
		)
		(fp_line
			(start 0.120396 0.2794)
			(end -0.12065 0.2794)
			(stroke
				(width 0.1)
				(type default)
			)
			(layer "F.Fab")
		)
		(fp_line
			(start 0.120396 0.3048)
			(end 0.120396 0.2794)
			(stroke
				(width 0.1)
				(type default)
			)
			(layer "F.Fab")
		)
		(fp_line
			(start 0.12065 -0.3048)
			(end 0.67945 -0.3048)
			(stroke
				(width 0.1)
				(type default)
			)
			(layer "F.Fab")
		)
		(fp_line
			(start 0.12065 -0.2794)
			(end 0.12065 -0.3048)
			(stroke
				(width 0.1)
				(type default)
			)
			(layer "F.Fab")
		)
		(fp_line
			(start 0.67945 -0.3048)
			(end 0.67945 0.3048)
			(stroke
				(width 0.1)
				(type default)
			)
			(layer "F.Fab")
		)
		(fp_line
			(start 0.67945 0.3048)
			(end 0.120396 0.3048)
			(stroke
				(width 0.1)
				(type default)
			)
			(layer "F.Fab")
		)
		(pad "1" smd circle
			(at -0.40005 0)
			(size 0 0)
			(layers "F.Cu" "F.Mask" "F.Paste")
			(net "P3V3_AUX")
		)
		(pad "2" smd circle
			(at 0.40005 0)
			(size 0 0)
			(layers "F.Cu" "F.Mask" "F.Paste")
			(net "GND")
		)
	)
	(footprint ""
		(layer "F.Cu")
		(at 413.512 -43.815 180)
		(property "Reference" "R54"
			(at 0 0 180)
			(layer "F.SilkS")
			(hide yes)
			(effects
				(font
					(size 1.27 1.27)
				)
			)
		)
		(property "Value" ""
			(at 0 0 180)
			(layer "F.Fab")
			(effects
				(font
					(size 1.27 1.27)
				)
			)
		)
		(duplicate_pad_numbers_are_jumpers no)
		(fp_line
			(start 0.7874 0.4064)
			(end -0.7874 0.4064)
			(stroke
				(width 0.1524)
				(type default)
			)
			(layer "F.SilkS")
		)
		(fp_line
			(start 0.7874 -0.4064)
			(end 0.7874 0.4064)
			(stroke
				(width 0.1524)
				(type default)
			)
			(layer "F.SilkS")
		)
		(fp_line
			(start -0.7874 0.4064)
			(end -0.7874 -0.4064)
			(stroke
				(width 0.1524)
				(type default)
			)
			(layer "F.SilkS")
		)
		(fp_line
			(start -0.7874 -0.4064)
			(end 0.7874 -0.4064)
			(stroke
				(width 0.1524)
				(type default)
			)
			(layer "F.SilkS")
		)
		(fp_line
			(start 0.67945 0.3048)
			(end 0.120396 0.3048)
			(stroke
				(width 0.1)
				(type default)
			)
			(layer "F.Fab")
		)
		(fp_line
			(start 0.67945 -0.3048)
			(end 0.67945 0.3048)
			(stroke
				(width 0.1)
				(type default)
			)
			(layer "F.Fab")
		)
		(fp_line
			(start 0.12065 -0.2794)
			(end 0.12065 -0.3048)
			(stroke
				(width 0.1)
				(type default)
			)
			(layer "F.Fab")
		)
		(fp_line
			(start 0.12065 -0.3048)
			(end 0.67945 -0.3048)
			(stroke
				(width 0.1)
				(type default)
			)
			(layer "F.Fab")
		)
		(fp_line
			(start 0.120396 0.3048)
			(end 0.120396 0.2794)
			(stroke
				(width 0.1)
				(type default)
			)
			(layer "F.Fab")
		)
		(fp_line
			(start 0.120396 0.2794)
			(end -0.12065 0.2794)
			(stroke
				(width 0.1)
				(type default)
			)
			(layer "F.Fab")
		)
		(fp_line
			(start -0.12065 0.3048)
			(end -0.67945 0.3048)
			(stroke
				(width 0.1)
				(type default)
			)
			(layer "F.Fab")
		)
		(fp_line
			(start -0.12065 0.2794)
			(end -0.12065 0.3048)
			(stroke
				(width 0.1)
				(type default)
			)
			(layer "F.Fab")
		)
		(fp_line
			(start -0.12065 -0.2794)
			(end 0.12065 -0.2794)
			(stroke
				(width 0.1)
				(type default)
			)
			(layer "F.Fab")
		)
		(fp_line
			(start -0.12065 -0.305054)
			(end -0.12065 -0.2794)
			(stroke
				(width 0.1)
				(type default)
			)
			(layer "F.Fab")
		)
		(fp_line
			(start -0.67945 0.3048)
			(end -0.67945 -0.305054)
			(stroke
				(width 0.1)
				(type default)
			)
			(layer "F.Fab")
		)
		(fp_line
			(start -0.67945 -0.305054)
			(end -0.12065 -0.305054)
			(stroke
				(width 0.1)
				(type default)
			)
			(layer "F.Fab")
		)
		(pad "1" smd circle
			(at -0.40005 0 180)
			(size 0 0)
			(layers "F.Cu" "F.Mask" "F.Paste")
			(net "PCA9555_A2")
		)
		(pad "2" smd circle
			(at 0.40005 0 180)
			(size 0 0)
			(layers "F.Cu" "F.Mask" "F.Paste")
			(net "GND")
		)
	)
	(footprint ""
		(layer "F.Cu")
		(at 413.07258 -29.24556)
		(property "Reference" "R5916"
			(at 0 0 0)
			(layer "F.SilkS")
			(hide yes)
			(effects
				(font
					(size 1.27 1.27)
				)
			)
		)
		(property "Value" ""
			(at 0 0 0)
			(layer "F.Fab")
			(effects
				(font
					(size 1.27 1.27)
				)
			)
		)
		(duplicate_pad_numbers_are_jumpers no)
		(fp_line
			(start -0.7874 -0.4064)
			(end 0.7874 -0.4064)
			(stroke
				(width 0.1524)
				(type default)
			)
			(layer "F.SilkS")
		)
		(fp_line
			(start -0.7874 0.4064)
			(end -0.7874 -0.4064)
			(stroke
				(width 0.1524)
				(type default)
			)
			(layer "F.SilkS")
		)
		(fp_line
			(start 0.7874 -0.4064)
			(end 0.7874 0.4064)
			(stroke
				(width 0.1524)
				(type default)
			)
			(layer "F.SilkS")
		)
		(fp_line
			(start 0.7874 0.4064)
			(end -0.7874 0.4064)
			(stroke
				(width 0.1524)
				(type default)
			)
			(layer "F.SilkS")
		)
		(fp_line
			(start -0.67945 -0.305054)
			(end -0.12065 -0.305054)
			(stroke
				(width 0.1)
				(type default)
			)
			(layer "F.Fab")
		)
		(fp_line
			(start -0.67945 0.3048)
			(end -0.67945 -0.305054)
			(stroke
				(width 0.1)
				(type default)
			)
			(layer "F.Fab")
		)
		(fp_line
			(start -0.12065 -0.305054)
			(end -0.12065 -0.2794)
			(stroke
				(width 0.1)
				(type default)
			)
			(layer "F.Fab")
		)
		(fp_line
			(start -0.12065 -0.2794)
			(end 0.12065 -0.2794)
			(stroke
				(width 0.1)
				(type default)
			)
			(layer "F.Fab")
		)
		(fp_line
			(start -0.12065 0.2794)
			(end -0.12065 0.3048)
			(stroke
				(width 0.1)
				(type default)
			)
			(layer "F.Fab")
		)
		(fp_line
			(start -0.12065 0.3048)
			(end -0.67945 0.3048)
			(stroke
				(width 0.1)
				(type default)
			)
			(layer "F.Fab")
		)
		(fp_line
			(start 0.120396 0.2794)
			(end -0.12065 0.2794)
			(stroke
				(width 0.1)
				(type default)
			)
			(layer "F.Fab")
		)
		(fp_line
			(start 0.120396 0.3048)
			(end 0.120396 0.2794)
			(stroke
				(width 0.1)
				(type default)
			)
			(layer "F.Fab")
		)
		(fp_line
			(start 0.12065 -0.3048)
			(end 0.67945 -0.3048)
			(stroke
				(width 0.1)
				(type default)
			)
			(layer "F.Fab")
		)
		(fp_line
			(start 0.12065 -0.2794)
			(end 0.12065 -0.3048)
			(stroke
				(width 0.1)
				(type default)
			)
			(layer "F.Fab")
		)
		(fp_line
			(start 0.67945 -0.3048)
			(end 0.67945 0.3048)
			(stroke
				(width 0.1)
				(type default)
			)
			(layer "F.Fab")
		)
		(fp_line
			(start 0.67945 0.3048)
			(end 0.120396 0.3048)
			(stroke
				(width 0.1)
				(type default)
			)
			(layer "F.Fab")
		)
		(pad "1" smd circle
			(at -0.40005 0)
			(size 0 0)
			(layers "F.Cu" "F.Mask" "F.Paste")
			(net "P3V3_AUX")
		)
		(pad "2" smd circle
			(at 0.40005 0)
			(size 0 0)
			(layers "F.Cu" "F.Mask" "F.Paste")
			(net "PWRGD_P12V_FAN_LED_R")
		)
	)
)
